(kicad_pcb
	(version 20260206)
	(generator "pcbnew")
	(generator_version "10.0")
	(general
		(thickness 1.6)
		(legacy_teardrops no)
	)
	(paper "A4")
	(title_block
		(title "Bryce Canyon_R.DPB_16317-1_OCP.brd")
		(comment 1 "Bryce Canyon / footprints 1098-1105 of 2099")
	)
	(layers
		(0 "F.Cu" signal "TOP")
		(4 "In1.Cu" signal "L2GND")
		(6 "In2.Cu" signal "L3")
		(8 "In3.Cu" signal "L4VCC")
		(10 "In4.Cu" signal "L5VCC")
		(12 "In5.Cu" signal "L6")
		(14 "In6.Cu" signal "L7GND")
		(2 "B.Cu" signal "BOTTOM")
		(9 "F.Adhes" user "F.Adhesive")
		(11 "B.Adhes" user "B.Adhesive")
		(13 "F.Paste" user "Package Geometry/Pastemask Top")
		(15 "B.Paste" user "Package Geometry/Pastemask Bottom")
		(5 "F.SilkS" user "Ref Des/Silkscreen Top")
		(7 "B.SilkS" user "Ref Des/Silkscreen Bottom")
		(1 "F.Mask" user "Board Geometry/Soldermask Top")
		(3 "B.Mask" user "Board Geometry/Soldermask Bottom")
		(17 "Dwgs.User" user "User.Drawings")
		(19 "Cmts.User" user "User.Comments")
		(21 "Eco1.User" user "User.Eco1")
		(23 "Eco2.User" user "User.Eco2")
		(25 "Edge.Cuts" user "Board Geometry/Outline")
		(27 "Margin" user)
		(31 "F.CrtYd" user "Package Geometry/Place Bound Top")
		(29 "B.CrtYd" user "Package Geometry/Place Bound Bottom")
		(35 "F.Fab" user "Ref Des/Assembly Top")
		(33 "B.Fab" user "Ref Des/Assembly Bottom")
	)
	(footprint ""
		(layer "F.Cu")
		(at 41.275 -6.3754 -90)
		(property "Reference" "R125"
			(at 0 0 270)
			(layer "F.SilkS")
			(hide yes)
			(effects
				(font
					(size 1.27 1.27)
				)
			)
		)
		(property "Value" "4K7R2F-GP"
			(at 0.064008 -3.993896 270)
			(unlocked yes)
			(layer "F.Fab")
			(hide yes)
			(effects
				(font
					(size 1.016 1.016)
					(thickness 0.1524)
				)
			)
		)
		(property "Device Type" "R402H16"
			(at 0.064008 -5.517896 270)
			(unlocked yes)
			(layer "F.Fab")
			(hide yes)
			(effects
				(font
					(size 1.016 1.016)
					(thickness 0.1524)
				)
			)
		)
		(duplicate_pad_numbers_are_jumpers no)
		(fp_line
			(start -0.508 -0.9398)
			(end -0.508 0.9398)
			(stroke
				(width 0.1524)
				(type default)
			)
			(layer "F.SilkS")
		)
		(fp_line
			(start 0.508 -0.9398)
			(end -0.508 -0.9398)
			(stroke
				(width 0.1524)
				(type default)
			)
			(layer "F.SilkS")
		)
		(fp_rect
			(start -0.508 0.9398)
			(end 0.508 -0.9398)
			(stroke
				(width 0)
				(type default)
			)
			(fill no)
			(layer "F.CrtYd")
		)
		(fp_rect
			(start -0.508 0.9398)
			(end 0.508 -0.9398)
			(stroke
				(width 0)
				(type default)
			)
			(fill no)
			(layer "F.Fab")
		)
		(pad "1" smd custom
			(at 0 -0.4445 270)
			(size 0.1397 0.1397)
			(layers "F.Cu" "F.Mask" "F.Paste")
			(net "TEMP1_A1")
			(options
				(clearance outline)
				(anchor circle)
			)
			(primitives
				(gr_poly
					(pts
						(arc
							(start -0.1778 -0.2794)
							(mid -0.249642 -0.249642)
							(end -0.2794 -0.1778)
						)
						(arc
							(start -0.2794 0.1778)
							(mid -0.249642 0.249642)
							(end -0.1778 0.2794)
						)
						(arc
							(start 0.1778 0.2794)
							(mid 0.249642 0.249642)
							(end 0.2794 0.1778)
						)
						(arc
							(start 0.2794 -0.1778)
							(mid 0.249642 -0.249642)
							(end 0.1778 -0.2794)
						)
					)
					(width 0)
					(fill yes)
				)
			)
		)
		(pad "2" smd custom
			(at 0 0.4445 270)
			(size 0.1397 0.1397)
			(layers "F.Cu" "F.Mask" "F.Paste")
			(net "GND")
			(options
				(clearance outline)
				(anchor circle)
			)
			(primitives
				(gr_poly
					(pts
						(arc
							(start -0.1778 -0.2794)
							(mid -0.249642 -0.249642)
							(end -0.2794 -0.1778)
						)
						(arc
							(start -0.2794 0.1778)
							(mid -0.249642 0.249642)
							(end -0.1778 0.2794)
						)
						(arc
							(start 0.1778 0.2794)
							(mid 0.249642 0.249642)
							(end 0.2794 0.1778)
						)
						(arc
							(start 0.2794 -0.1778)
							(mid 0.249642 -0.249642)
							(end 0.1778 -0.2794)
						)
					)
					(width 0)
					(fill yes)
				)
			)
		)
	)
	(footprint ""
		(layer "F.Cu")
		(at 190.0428 -146.6342)
		(property "Reference" "C258"
			(at 0 0 0)
			(layer "F.SilkS")
			(hide yes)
			(effects
				(font
					(size 1.27 1.27)
				)
			)
		)
		(property "Value" "SCD01U50V2KX-1GP"
			(at 1.1811 -2.7051 0)
			(unlocked yes)
			(layer "F.Fab")
			(hide yes)
			(effects
				(font
					(size 1.016 1.016)
					(thickness 0.1524)
				)
			)
		)
		(property "Device Type" "C402H22"
			(at 1.1811 -4.2291 0)
			(unlocked yes)
			(layer "F.Fab")
			(hide yes)
			(effects
				(font
					(size 1.016 1.016)
					(thickness 0.1524)
				)
			)
		)
		(duplicate_pad_numbers_are_jumpers no)
		(fp_rect
			(start -0.4318 0.9525)
			(end 0.4318 -0.9525)
			(stroke
				(width 0)
				(type default)
			)
			(fill no)
			(layer "F.CrtYd")
		)
		(fp_rect
			(start -0.4318 0.9525)
			(end 0.4318 -0.9525)
			(stroke
				(width 0)
				(type default)
			)
			(fill no)
			(layer "F.Fab")
		)
		(pad "1" smd custom
			(at 0 -0.4445)
			(size 0.1524 0.1524)
			(layers "F.Cu" "F.Mask" "F.Paste")
			(net "HDD_PRSNT_17")
			(options
				(clearance outline)
				(anchor circle)
			)
			(primitives
				(gr_poly
					(pts
						(arc
							(start 0.3048 -0.2032)
							(mid 0.275042 -0.275042)
							(end 0.2032 -0.3048)
						)
						(arc
							(start -0.2032 -0.3048)
							(mid -0.275042 -0.275042)
							(end -0.3048 -0.2032)
						)
						(arc
							(start -0.3048 0.2032)
							(mid -0.275042 0.275042)
							(end -0.2032 0.3048)
						)
						(arc
							(start 0.2032 0.3048)
							(mid 0.275042 0.275042)
							(end 0.3048 0.2032)
						)
					)
					(width 0)
					(fill yes)
				)
			)
		)
		(pad "2" smd custom
			(at 0 0.4445)
			(size 0.1524 0.1524)
			(layers "F.Cu" "F.Mask" "F.Paste")
			(net "GND")
			(options
				(clearance outline)
				(anchor circle)
			)
			(primitives
				(gr_poly
					(pts
						(arc
							(start 0.3048 -0.2032)
							(mid 0.275042 -0.275042)
							(end 0.2032 -0.3048)
						)
						(arc
							(start -0.2032 -0.3048)
							(mid -0.275042 -0.275042)
							(end -0.3048 -0.2032)
						)
						(arc
							(start -0.3048 0.2032)
							(mid -0.275042 0.275042)
							(end -0.2032 0.3048)
						)
						(arc
							(start 0.2032 0.3048)
							(mid 0.275042 0.275042)
							(end 0.3048 0.2032)
						)
					)
					(width 0)
					(fill yes)
				)
			)
		)
	)
	(footprint ""
		(layer "F.Cu")
		(at 300.199806 -243.999766)
		(property "Reference" ""
			(at 0 0 0)
			(layer "F.SilkS")
			(hide yes)
			(effects
				(font
					(size 1.27 1.27)
				)
			)
		)
		(property "Value" "*"
			(at -8.398764 -8.057642 0)
			(unlocked yes)
			(layer "F.Fab")
			(hide yes)
			(effects
				(font
					(size 1.016 1.016)
					(thickness 0.1524)
				)
			)
		)
		(duplicate_pad_numbers_are_jumpers no)
		(fp_poly
			(pts
				(arc
					(start 7.3152 0)
					(mid 0 7.3152)
					(end -7.3152 0)
				)
				(arc
					(start -7.3152 -5.9944)
					(mid 0 -13.3096)
					(end 7.3152 -5.9944)
				)
			)
			(stroke
				(width 0)
				(type default)
			)
			(fill no)
			(layer "B.CrtYd")
		)
		(fp_poly
			(pts
				(arc
					(start 7.3152 0)
					(mid 0 7.3152)
					(end -7.3152 0)
				)
				(arc
					(start -7.3152 -5.9944)
					(mid 0 -13.3096)
					(end 7.3152 -5.9944)
				)
			)
			(stroke
				(width 0)
				(type default)
			)
			(fill no)
			(layer "F.CrtYd")
		)
		(fp_poly
			(pts
				(arc
					(start 7.3152 0)
					(mid 0 7.3152)
					(end -7.3152 0)
				)
				(arc
					(start -7.3152 -5.9944)
					(mid 0 -13.3096)
					(end 7.3152 -5.9944)
				)
			)
			(stroke
				(width 0)
				(type default)
			)
			(fill no)
			(layer "B.Fab")
		)
		(fp_poly
			(pts
				(arc
					(start 7.3152 0)
					(mid 0 7.3152)
					(end -7.3152 0)
				)
				(arc
					(start -7.3152 -5.9944)
					(mid 0 -13.3096)
					(end 7.3152 -5.9944)
				)
			)
			(stroke
				(width 0)
				(type default)
			)
			(fill no)
			(layer "F.Fab")
		)
		(pad "1" thru_hole oval
			(at 0 0)
			(size 14.0208 20.0152)
			(drill 0.0254
				(offset 0 -2.9972)
			)
			(layers "*.Cu" "*.Mask")
			(remove_unused_layers no)
			(net "Net_21")
			(clearance -1.002284)
			(thermal_gap 0.1524)
			(padstack
				(mode front_inner_back)
				(layer "Inner"
					(shape custom)
					(size 2.928012 2.928012)
					(options
						(anchor circle)
					)
					(primitives
						(gr_poly
							(pts
								(arc
									(start 4.571746 -2.084324)
									(mid 0.000333 7.430372)
									(end -4.571492 -2.084324)
								)
								(arc
									(start -4.571492 -2.084324)
									(mid -3.570296 -3.611977)
									(end -2.875026 -5.30098)
								)
								(arc
									(start -2.875026 -5.30098)
									(mid 0.000217 -7.43089)
									(end 2.87528 -5.30098)
								)
								(arc
									(start 2.87528 -5.30098)
									(mid 3.570511 -3.611956)
									(end 4.571746 -2.084324)
								)
							)
							(width 0)
							(fill yes)
						)
					)
					(clearance 0.1524)
				)
				(layer "B.Cu"
					(shape oval)
					(size 14.0208 20.0152)
					(offset 0 -2.9972)
					(clearance -1.002284)
				)
			)
		)
		(zone
			(layers "F.Cu" "B.Cu" "In1.Cu" "In2.Cu" "In3.Cu" "In4.Cu" "In5.Cu" "In6.Cu")
			(hatch none 0.5)
			(connect_pads
				(clearance 0)
			)
			(min_thickness 0.25)
			(keepout
				(tracks not_allowed)
				(vias allowed)
				(pads allowed)
				(copperpour not_allowed)
				(footprints allowed)
			)
			(placement
				(enabled no)
				(sheetname "")
			)
			(fill
				(thermal_gap 0.5)
				(thermal_bridge_width 0.5)
				(island_removal_mode 0)
			)
			(polygon
				(pts
					(arc
						(start 293.189406 -249.994166)
						(mid 300.199806 -257.004566)
						(end 307.210206 -249.994166)
					)
					(arc
						(start 307.210206 -243.999766)
						(mid 300.199806 -236.989366)
						(end 293.189406 -243.999766)
					)
				)
			)
		)
	)
	(footprint ""
		(layer "F.Cu")
		(at 144.526 -99.314)
		(property "Reference" "R421"
			(at 0 0 0)
			(layer "F.SilkS")
			(hide yes)
			(effects
				(font
					(size 1.27 1.27)
				)
			)
		)
		(property "Value" "91R3F-1-GP"
			(at -0.0254 -2.5146 0)
			(unlocked yes)
			(layer "F.Fab")
			(hide yes)
			(effects
				(font
					(size 1.016 1.016)
					(thickness 0.1524)
				)
			)
		)
		(property "Device Type" "R603H22"
			(at -0.0254 -4.0386 0)
			(unlocked yes)
			(layer "F.Fab")
			(hide yes)
			(effects
				(font
					(size 1.016 1.016)
					(thickness 0.1524)
				)
			)
		)
		(duplicate_pad_numbers_are_jumpers no)
		(fp_line
			(start -0.4826 0)
			(end -0.2032 0)
			(stroke
				(width 0.2032)
				(type default)
			)
			(layer "F.SilkS")
		)
		(fp_line
			(start 0.2032 0)
			(end 0.4826 0)
			(stroke
				(width 0.2032)
				(type default)
			)
			(layer "F.SilkS")
		)
		(fp_rect
			(start -0.5842 1.3335)
			(end 0.5842 -1.3335)
			(stroke
				(width 0)
				(type default)
			)
			(fill no)
			(layer "F.CrtYd")
		)
		(fp_rect
			(start -0.5842 1.3335)
			(end 0.5842 -1.3335)
			(stroke
				(width 0)
				(type default)
			)
			(fill no)
			(layer "F.Fab")
		)
		(pad "1" smd custom
			(at 0 -0.762)
			(size 0.2159 0.2159)
			(layers "F.Cu" "F.Mask" "F.Paste")
			(net "P5V_B_2")
			(options
				(clearance outline)
				(anchor circle)
			)
			(primitives
				(gr_poly
					(pts
						(arc
							(start -0.3302 -0.4318)
							(mid -0.402042 -0.402042)
							(end -0.4318 -0.3302)
						)
						(arc
							(start -0.4318 0.3302)
							(mid -0.402042 0.402042)
							(end -0.3302 0.4318)
						)
						(arc
							(start 0.3302 0.4318)
							(mid 0.402042 0.402042)
							(end 0.4318 0.3302)
						)
						(arc
							(start 0.4318 -0.3302)
							(mid 0.402042 -0.402042)
							(end 0.3302 -0.4318)
						)
					)
					(width 0)
					(fill yes)
				)
			)
		)
		(pad "2" smd custom
			(at 0 0.762)
			(size 0.2159 0.2159)
			(layers "F.Cu" "F.Mask" "F.Paste")
			(net "DRV_ACT_16")
			(options
				(clearance outline)
				(anchor circle)
			)
			(primitives
				(gr_poly
					(pts
						(arc
							(start -0.3302 -0.4318)
							(mid -0.402042 -0.402042)
							(end -0.4318 -0.3302)
						)
						(arc
							(start -0.4318 0.3302)
							(mid -0.402042 0.402042)
							(end -0.3302 0.4318)
						)
						(arc
							(start 0.3302 0.4318)
							(mid 0.402042 0.402042)
							(end 0.4318 0.3302)
						)
						(arc
							(start 0.4318 -0.3302)
							(mid 0.402042 -0.402042)
							(end 0.3302 -0.4318)
						)
					)
					(width 0)
					(fill yes)
				)
			)
		)
	)
	(footprint ""
		(layer "F.Cu")
		(at 394.716 -250.5964 -90)
		(property "Reference" "C142"
			(at 0 0 270)
			(layer "F.SilkS")
			(hide yes)
			(effects
				(font
					(size 1.27 1.27)
				)
			)
		)
		(property "Value" "SCD033U25V2KX-GP"
			(at 1.1811 -2.7051 270)
			(unlocked yes)
			(layer "F.Fab")
			(hide yes)
			(effects
				(font
					(size 1.016 1.016)
					(thickness 0.1524)
				)
			)
		)
		(property "Device Type" "C402H22"
			(at 1.1811 -4.2291 270)
			(unlocked yes)
			(layer "F.Fab")
			(hide yes)
			(effects
				(font
					(size 1.016 1.016)
					(thickness 0.1524)
				)
			)
		)
		(duplicate_pad_numbers_are_jumpers no)
		(fp_rect
			(start -0.4318 0.9525)
			(end 0.4318 -0.9525)
			(stroke
				(width 0)
				(type default)
			)
			(fill no)
			(layer "F.CrtYd")
		)
		(fp_rect
			(start -0.4318 0.9525)
			(end 0.4318 -0.9525)
			(stroke
				(width 0)
				(type default)
			)
			(fill no)
			(layer "F.Fab")
		)
		(pad "1" smd custom
			(at 0 -0.4445 270)
			(size 0.1524 0.1524)
			(layers "F.Cu" "F.Mask" "F.Paste")
			(net "SW_HDD_P8")
			(options
				(clearance outline)
				(anchor circle)
			)
			(primitives
				(gr_poly
					(pts
						(arc
							(start 0.3048 -0.2032)
							(mid 0.275042 -0.275042)
							(end 0.2032 -0.3048)
						)
						(arc
							(start -0.2032 -0.3048)
							(mid -0.275042 -0.275042)
							(end -0.3048 -0.2032)
						)
						(arc
							(start -0.3048 0.2032)
							(mid -0.275042 0.275042)
							(end -0.2032 0.3048)
						)
						(arc
							(start 0.2032 0.3048)
							(mid 0.275042 0.275042)
							(end 0.3048 0.2032)
						)
					)
					(width 0)
					(fill yes)
				)
			)
		)
		(pad "2" smd custom
			(at 0 0.4445 270)
			(size 0.1524 0.1524)
			(layers "F.Cu" "F.Mask" "F.Paste")
			(net "GND")
			(options
				(clearance outline)
				(anchor circle)
			)
			(primitives
				(gr_poly
					(pts
						(arc
							(start 0.3048 -0.2032)
							(mid 0.275042 -0.275042)
							(end 0.2032 -0.3048)
						)
						(arc
							(start -0.2032 -0.3048)
							(mid -0.275042 -0.275042)
							(end -0.3048 -0.2032)
						)
						(arc
							(start -0.3048 0.2032)
							(mid -0.275042 0.275042)
							(end -0.2032 0.3048)
						)
						(arc
							(start 0.2032 0.3048)
							(mid 0.275042 0.275042)
							(end 0.3048 0.2032)
						)
					)
					(width 0)
					(fill yes)
				)
			)
		)
	)
	(footprint ""
		(layer "F.Cu")
		(at 477.0374 -37.9984)
		(property "Reference" "TP196"
			(at 0 0 0)
			(layer "F.SilkS")
			(hide yes)
			(effects
				(font
					(size 1.27 1.27)
				)
			)
		)
		(property "Value" "*"
			(at -0.0508 -1.6764 0)
			(unlocked yes)
			(layer "F.Fab")
			(hide yes)
			(effects
				(font
					(size 1.016 1.016)
					(thickness 0.1524)
				)
			)
		)
		(property "Device Type" "TPAD32"
			(at -0.0508 -3.2004 0)
			(unlocked yes)
			(layer "F.Fab")
			(hide yes)
			(effects
				(font
					(size 1.016 1.016)
					(thickness 0.1524)
				)
			)
		)
		(duplicate_pad_numbers_are_jumpers no)
		(fp_poly
			(pts
				(arc
					(start 0.4064 0)
					(mid -0.4064 0)
					(end 0.4064 0)
				)
			)
			(stroke
				(width 0)
				(type default)
			)
			(fill no)
			(layer "F.CrtYd")
		)
		(fp_poly
			(pts
				(arc
					(start 0.7112 0)
					(mid -0.7112 0)
					(end 0.7112 0)
				)
			)
			(stroke
				(width 0)
				(type default)
			)
			(fill no)
			(layer "F.Fab")
		)
		(pad "1" smd circle
			(at 0 0)
			(size 0.8128 0.8128)
			(layers "F.Cu" "F.Mask" "F.Paste")
			(net "ACT_HDD_35")
		)
	)
	(footprint ""
		(layer "F.Cu")
		(at 57.244996 -363.22 90)
		(property "Reference" "C522"
			(at 0 0 90)
			(layer "F.SilkS")
			(hide yes)
			(effects
				(font
					(size 1.27 1.27)
				)
			)
		)
		(property "Value" "SC1U25V3KX-GP"
			(at 0 -2.8194 90)
			(unlocked yes)
			(layer "F.Fab")
			(hide yes)
			(effects
				(font
					(size 1.016 1.016)
					(thickness 0.1524)
				)
			)
		)
		(property "Device Type" "C603H36"
			(at 0 -4.3434 90)
			(unlocked yes)
			(layer "F.Fab")
			(hide yes)
			(effects
				(font
					(size 1.016 1.016)
					(thickness 0.1524)
				)
			)
		)
		(duplicate_pad_numbers_are_jumpers no)
		(fp_line
			(start 0.508 0)
			(end -0.508 0)
			(stroke
				(width 0.2032)
				(type default)
			)
			(layer "F.SilkS")
		)
		(fp_rect
			(start -0.5842 1.3335)
			(end 0.5842 -1.3335)
			(stroke
				(width 0)
				(type default)
			)
			(fill no)
			(layer "F.CrtYd")
		)
		(fp_rect
			(start -0.5842 1.3335)
			(end 0.5842 -1.3335)
			(stroke
				(width 0)
				(type default)
			)
			(fill no)
			(layer "F.Fab")
		)
		(pad "1" smd custom
			(at 0 -0.762 90)
			(size 0.2159 0.2159)
			(layers "F.Cu" "F.Mask" "F.Paste")
			(net "P12V_FAN0")
			(options
				(clearance outline)
				(anchor circle)
			)
			(primitives
				(gr_poly
					(pts
						(arc
							(start -0.3302 -0.4318)
							(mid -0.402042 -0.402042)
							(end -0.4318 -0.3302)
						)
						(arc
							(start -0.4318 0.3302)
							(mid -0.402042 0.402042)
							(end -0.3302 0.4318)
						)
						(arc
							(start 0.3302 0.4318)
							(mid 0.402042 0.402042)
							(end 0.4318 0.3302)
						)
						(arc
							(start 0.4318 -0.3302)
							(mid 0.402042 -0.402042)
							(end 0.3302 -0.4318)
						)
					)
					(width 0)
					(fill yes)
				)
			)
		)
		(pad "2" smd custom
			(at 0 0.762 90)
			(size 0.2159 0.2159)
			(layers "F.Cu" "F.Mask" "F.Paste")
			(net "GND")
			(options
				(clearance outline)
				(anchor circle)
			)
			(primitives
				(gr_poly
					(pts
						(arc
							(start -0.3302 -0.4318)
							(mid -0.402042 -0.402042)
							(end -0.4318 -0.3302)
						)
						(arc
							(start -0.4318 0.3302)
							(mid -0.402042 0.402042)
							(end -0.3302 0.4318)
						)
						(arc
							(start 0.3302 0.4318)
							(mid 0.402042 0.402042)
							(end 0.4318 0.3302)
						)
						(arc
							(start 0.4318 -0.3302)
							(mid 0.402042 -0.402042)
							(end 0.3302 -0.4318)
						)
					)
					(width 0)
					(fill yes)
				)
			)
		)
	)
	(footprint ""
		(layer "F.Cu")
		(at 386.41655 -132.437124)
		(property "Reference" "VIA42"
			(at 0 0 0)
			(layer "F.SilkS")
			(hide yes)
			(effects
				(font
					(size 1.27 1.27)
				)
			)
		)
		(property "Value" "100OHM-8L-2D36MM-L16-GP"
			(at -3.4036 -0.4572 0)
			(unlocked yes)
			(layer "F.Fab")
			(hide yes)
			(effects
				(font
					(size 1.016 1.016)
					(thickness 0.1524)
				)
			)
		)
		(property "Device Type" "VIA-PCIE-4P-427097"
			(at -3.4036 -1.9812 0)
			(unlocked yes)
			(layer "F.Fab")
			(hide yes)
			(effects
				(font
					(size 1.016 1.016)
					(thickness 0.1524)
				)
			)
		)
		(duplicate_pad_numbers_are_jumpers no)
		(fp_rect
			(start -2.1336 0.4826)
			(end 2.1336 -0.4826)
			(stroke
				(width 0)
				(type default)
			)
			(fill no)
			(layer "F.CrtYd")
		)
		(fp_rect
			(start -2.1336 0.4826)
			(end 2.1336 -0.4826)
			(stroke
				(width 0)
				(type default)
			)
			(fill no)
			(layer "F.Fab")
		)
		(pad "1" thru_hole circle
			(at -1.651 0)
			(size 0.508 0.508)
			(drill 0.254)
			(layers "*.Cu" "*.Mask")
			(remove_unused_layers no)
			(net "GND")
			(clearance 0.2286)
			(thermal_gap 0.2286)
		)
		(pad "2" thru_hole circle
			(at -0.635 0)
			(size 0.508 0.508)
			(drill 0.254)
			(layers "*.Cu" "*.Mask")
			(remove_unused_layers no)
			(net "PHY_DRV_B_TO_SCC_B_20_DP")
			(clearance 0.2286)
			(thermal_gap 0.2286)
		)
		(pad "3" thru_hole circle
			(at 0.635 0)
			(size 0.508 0.508)
			(drill 0.254)
			(layers "*.Cu" "*.Mask")
			(remove_unused_layers no)
			(net "PHY_DRV_B_TO_SCC_B_20_DN")
			(clearance 0.2286)
			(thermal_gap 0.2286)
		)
		(pad "4" thru_hole circle
			(at 1.651 0)
			(size 0.508 0.508)
			(drill 0.254)
			(layers "*.Cu" "*.Mask")
			(remove_unused_layers no)
			(net "GND")
			(clearance 0.2286)
			(thermal_gap 0.2286)
		)
	)
)
